#ISCELL
  mstr_misc dns *
  *
#ISCELL
  pure_quanta quanta_title_block_c *
  *
#CELL
  pure_quanta isl99390frztr5935 *
  page186_i1
#ISCELL
  standard offpage *
  page186_i10
#CELL
  pure_quanta q_capp *
  page186_i106
#CELL
  pure_quanta q_capp *
  page186_i107
#ISCELL
  pure_quanta_power vcc_core *
  page186_i109
#CELL
  pure_quanta q_res *
  page186_i11
#ISCELL
  pure_quanta_power universal_gnd *
  page186_i110
#CELL
  pure_quanta q_capp *
  page186_i112
#CELL
  pure_quanta q_cap *
  page186_i113
#CELL
  pure_quanta q_cap *
  page186_i114
#CELL
  pure_quanta q_cap *
  page186_i115
#ISCELL
  pure_quanta_power universal_gnd *
  page186_i116
#ISCELL
  pure_quanta_power universal_gnd *
  page186_i117
#CELL
  pure_quanta q_res *
  page186_i118
#CELL
  pure_quanta q_cap *
  page186_i119
#ISCELL
  pure_quanta_power universal_gnd *
  page186_i12
#ISCELL
  pure_quanta_power vcc_core *
  page186_i120
#CELL
  pure_quanta q_capp *
  page186_i121
#ISCELL
  standard offpage *
  page186_i122
#ISCELL
  pure_quanta_power universal_gnd *
  page186_i123
#CELL
  pure_quanta q_res *
  page186_i124
#CELL
  pure_quanta q_cap *
  page186_i125
#ISCELL
  pure_quanta_power universal_gnd *
  page186_i126
#CELL
  pure_quanta q_res *
  page186_i127
#CELL
  pure_quanta q_cap *
  page186_i128
#ISCELL
  standard offpage *
  page186_i129
#CELL
  pure_quanta q_cap *
  page186_i13
#CELL
  pure_quanta q_res *
  page186_i130
#ISCELL
  pure_quanta_power vcc_core *
  page186_i131
#CELL
  pure_quanta q_res *
  page186_i132
#ISCELL
  pure_quanta_power vcc_core *
  page186_i133
#ISCELL
  pure_quanta_power vcc_core *
  page186_i134
#CELL
  pure_quanta q_res *
  page186_i135
#ISCELL
  pure_quanta_power universal_gnd *
  page186_i14
#ISCELL
  pure_quanta_power universal_gnd *
  page186_i15
#CELL
  pure_quanta q_res *
  page186_i16
#CELL
  pure_quanta q_cap *
  page186_i17
#CELL
  pure_quanta q_cap *
  page186_i18
#CELL
  pure_quanta q_cap *
  page186_i19
#CELL
  pure_quanta q_cap *
  page186_i2
#CELL
  pure_quanta q_cap *
  page186_i20
#CELL
  pure_quanta q_cap *
  page186_i21
#ISCELL
  pure_quanta_power universal_gnd *
  page186_i23
#CELL
  pure_quanta q_inductor *
  page186_i24
#ISCELL
  pure_quanta_power vcc_core *
  page186_i25
#CELL
  pure_quanta q_capp *
  page186_i26
#CELL
  pure_quanta q_capp *
  page186_i27
#CELL
  pure_quanta q_res *
  page186_i3
#ISCELL
  pure_quanta_power vcc_core *
  page186_i30
#CELL
  pure_quanta q_inductor4p_14 *
  page186_i31
#CELL
  pure_quanta q_cap *
  page186_i32
#CELL
  pure_quanta q_cap *
  page186_i33
#CELL
  pure_quanta q_cap *
  page186_i35
#ISCELL
  pure_quanta_power universal_gnd *
  page186_i36
#ISCELL
  pure_quanta_power vcc_core *
  page186_i37
#ISCELL
  standard offpage *
  page186_i39
#CELL
  pure_quanta q_cap *
  page186_i4
#CELL
  pure_quanta q_res *
  page186_i40
#ISCELL
  standard offpage *
  page186_i41
#CELL
  pure_quanta isl99390frztr5935 *
  page186_i46
#ISCELL
  pure_quanta_power vcc_core *
  page186_i47
#CELL
  pure_quanta q_cap *
  page186_i48
#ISCELL
  pure_quanta_power universal_gnd *
  page186_i49
#ISCELL
  pure_quanta_power universal_gnd *
  page186_i5
#CELL
  pure_quanta q_cap *
  page186_i50
#ISCELL
  pure_quanta_power vcc_core *
  page186_i54
#ISCELL
  pure_quanta_power universal_gnd *
  page186_i56
#CELL
  pure_quanta q_cap *
  page186_i62
#CELL
  pure_quanta q_inductor4p_14 *
  page186_i63
#CELL
  pure_quanta q_cap *
  page186_i64
#CELL
  pure_quanta q_cap *
  page186_i65
#CELL
  pure_quanta q_cap *
  page186_i66
#CELL
  pure_quanta q_cap *
  page186_i67
#CELL
  pure_quanta q_res *
  page186_i68
#ISCELL
  pure_quanta_power universal_gnd *
  page186_i7
#CELL
  pure_quanta q_res *
  page186_i71
#CELL
  pure_quanta q_res *
  page186_i75
#ISCELL
  standard offpage *
  page186_i8
#ISCELL
  standard offpage *
  page186_i80
#ISCELL
  standard offpage *
  page186_i83
#ISCELL
  pure_quanta_power universal_gnd *
  page186_i84
#ISCELL
  pure_quanta_power universal_gnd *
  page186_i85
#CELL
  pure_quanta q_cap *
  page186_i86
#ISCELL
  standard offpage *
  page186_i87
#ISCELL
  pure_quanta_power universal_gnd *
  page186_i88
#ISCELL
  standard offpage *
  page186_i89
#ISCELL
  standard offpage *
  page186_i9
#ISCELL
  standard offpage *
  page186_i91
#CELL
  pure_quanta q_capp *
  page186_i92
